(kicad_pcb
	(version 20260206)
	(generator "pcbnew")
	(generator_version "10.0")
	(general
		(thickness 1.6)
		(legacy_teardrops no)
	)
	(paper "A4")
	(title_block
		(title "dpb — 14545-sa.0730WZS0815.brd")
		(comment 1 "Honey Badger (Wiwynn) / footprints 167-174 of 1066")
	)
	(layers
		(0 "F.Cu" signal "TOP")
		(4 "In1.Cu" signal "L2GND")
		(6 "In2.Cu" signal "L3")
		(8 "In3.Cu" signal "L4VCC")
		(10 "In4.Cu" signal "L5VCC")
		(12 "In5.Cu" signal "L6")
		(14 "In6.Cu" signal "L7GND")
		(2 "B.Cu" signal "BOTTOM")
		(9 "F.Adhes" user "F.Adhesive")
		(11 "B.Adhes" user "B.Adhesive")
		(13 "F.Paste" user "Package Geometry/Pastemask Top")
		(15 "B.Paste" user "Package Geometry/Pastemask Bottom")
		(5 "F.SilkS" user "Ref Des/Silkscreen Top")
		(7 "B.SilkS" user "Ref Des/Silkscreen Bottom")
		(1 "F.Mask" user "Board Geometry/Soldermask Top")
		(3 "B.Mask" user "Board Geometry/Soldermask Bottom")
		(17 "Dwgs.User" user "User.Drawings")
		(19 "Cmts.User" user "User.Comments")
		(21 "Eco1.User" user "User.Eco1")
		(23 "Eco2.User" user "User.Eco2")
		(25 "Edge.Cuts" user "Board Geometry/Outline")
		(27 "Margin" user)
		(31 "F.CrtYd" user "Package Geometry/Place Bound Top")
		(29 "B.CrtYd" user "Package Geometry/Place Bound Bottom")
		(35 "F.Fab" user "Ref Des/Assembly Top")
		(33 "B.Fab" user "Ref Des/Assembly Bottom")
	)
	(footprint ""
		(layer "F.Cu")
		(at 52.196746 -25.2857)
		(property "Reference" "PR25"
			(at 0 0 0)
			(layer "F.SilkS")
			(hide yes)
			(effects
				(font
					(size 1.27 1.27)
				)
			)
		)
		(property "Value" "10KR2F-2-GP"
			(at 0.064008 -3.993896 0)
			(unlocked yes)
			(layer "F.Fab")
			(hide yes)
			(effects
				(font
					(size 1.016 1.016)
					(thickness 0.1524)
				)
			)
		)
		(property "Device Type" "R402H16"
			(at 0.064008 -5.517896 0)
			(unlocked yes)
			(layer "F.Fab")
			(hide yes)
			(effects
				(font
					(size 1.016 1.016)
					(thickness 0.1524)
				)
			)
		)
		(duplicate_pad_numbers_are_jumpers no)
		(fp_line
			(start -0.508 -0.9398)
			(end -0.508 0.9398)
			(stroke
				(width 0.1524)
				(type default)
			)
			(layer "F.SilkS")
		)
		(fp_line
			(start 0.508 -0.9398)
			(end -0.508 -0.9398)
			(stroke
				(width 0.1524)
				(type default)
			)
			(layer "F.SilkS")
		)
		(fp_rect
			(start -0.508 0.9398)
			(end 0.508 -0.9398)
			(stroke
				(width 0)
				(type default)
			)
			(fill no)
			(layer "F.CrtYd")
		)
		(fp_rect
			(start -0.508 0.9398)
			(end 0.508 -0.9398)
			(stroke
				(width 0)
				(type default)
			)
			(fill no)
			(layer "F.Fab")
		)
		(pad "1" smd custom
			(at 0 -0.4445)
			(size 0.1397 0.1397)
			(layers "F.Cu" "F.Mask" "F.Paste")
			(net "P5VB_12VIN")
			(options
				(clearance outline)
				(anchor circle)
			)
			(primitives
				(gr_poly
					(pts
						(arc
							(start -0.1778 -0.2794)
							(mid -0.249642 -0.249642)
							(end -0.2794 -0.1778)
						)
						(arc
							(start -0.2794 0.1778)
							(mid -0.249642 0.249642)
							(end -0.1778 0.2794)
						)
						(arc
							(start 0.1778 0.2794)
							(mid 0.249642 0.249642)
							(end 0.2794 0.1778)
						)
						(arc
							(start 0.2794 -0.1778)
							(mid 0.249642 -0.249642)
							(end 0.1778 -0.2794)
						)
					)
					(width 0)
					(fill yes)
				)
			)
		)
		(pad "2" smd custom
			(at 0 0.4445)
			(size 0.1397 0.1397)
			(layers "F.Cu" "F.Mask" "F.Paste")
			(net "P5VB_EN")
			(options
				(clearance outline)
				(anchor circle)
			)
			(primitives
				(gr_poly
					(pts
						(arc
							(start -0.1778 -0.2794)
							(mid -0.249642 -0.249642)
							(end -0.2794 -0.1778)
						)
						(arc
							(start -0.2794 0.1778)
							(mid -0.249642 0.249642)
							(end -0.1778 0.2794)
						)
						(arc
							(start 0.1778 0.2794)
							(mid 0.249642 0.249642)
							(end 0.2794 0.1778)
						)
						(arc
							(start 0.2794 -0.1778)
							(mid 0.249642 -0.249642)
							(end 0.1778 -0.2794)
						)
					)
					(width 0)
					(fill yes)
				)
			)
		)
	)
	(footprint ""
		(layer "F.Cu")
		(at 215.518746 -184.0357 -90)
		(property "Reference" "R154"
			(at 0 0 270)
			(layer "F.SilkS")
			(hide yes)
			(effects
				(font
					(size 1.27 1.27)
				)
			)
		)
		(property "Value" "2R2010J-1-GP"
			(at 0.254 -8.0772 270)
			(unlocked yes)
			(layer "F.Fab")
			(hide yes)
			(effects
				(font
					(size 1.016 1.016)
					(thickness 0.1524)
				)
			)
		)
		(property "Device Type" "R2010H28"
			(at 0.254 -9.6774 270)
			(unlocked yes)
			(layer "F.Fab")
			(hide yes)
			(effects
				(font
					(size 1.016 1.016)
					(thickness 0.1524)
				)
			)
		)
		(duplicate_pad_numbers_are_jumpers no)
		(fp_line
			(start -1.651 3.302)
			(end 1.651 3.302)
			(stroke
				(width 0.1524)
				(type default)
			)
			(layer "F.SilkS")
		)
		(fp_line
			(start 1.651 3.302)
			(end 1.651 -3.302)
			(stroke
				(width 0.1524)
				(type default)
			)
			(layer "F.SilkS")
		)
		(fp_line
			(start -1.651 -3.302)
			(end -1.651 3.302)
			(stroke
				(width 0.1524)
				(type default)
			)
			(layer "F.SilkS")
		)
		(fp_line
			(start 1.651 -3.302)
			(end -1.651 -3.302)
			(stroke
				(width 0.1524)
				(type default)
			)
			(layer "F.SilkS")
		)
		(fp_rect
			(start -1.7272 -3.3782)
			(end 1.7272 3.3782)
			(stroke
				(width 0)
				(type default)
			)
			(fill no)
			(layer "F.CrtYd")
		)
		(fp_poly
			(pts
				(xy 1.7272 3.3782) (xy 1.7272 -3.3782) (xy -1.7272 -3.3782) (xy -1.7272 3.3782)
			)
			(stroke
				(width 0)
				(type default)
			)
			(fill no)
			(layer "F.Fab")
		)
		(pad "1" smd rect
			(at 0 -2.3495 270)
			(size 2.794 1.143)
			(layers "F.Cu" "F.Mask" "F.Paste")
			(net "12V_PRE_3")
		)
		(pad "2" smd rect
			(at 0 2.3495 270)
			(size 2.794 1.143)
			(layers "F.Cu" "F.Mask" "F.Paste")
			(net "P12V_HDD3")
		)
	)
	(footprint ""
		(layer "F.Cu")
		(at 83.82 -500.761)
		(property "Reference" "R568"
			(at 0 0 0)
			(layer "F.SilkS")
			(hide yes)
			(effects
				(font
					(size 1.27 1.27)
				)
			)
		)
		(property "Value" "300KR2F-GP"
			(at 0.064008 -3.993896 0)
			(unlocked yes)
			(layer "F.Fab")
			(hide yes)
			(effects
				(font
					(size 1.016 1.016)
					(thickness 0.1524)
				)
			)
		)
		(property "Device Type" "R402H16"
			(at 0.064008 -5.517896 0)
			(unlocked yes)
			(layer "F.Fab")
			(hide yes)
			(effects
				(font
					(size 1.016 1.016)
					(thickness 0.1524)
				)
			)
		)
		(duplicate_pad_numbers_are_jumpers no)
		(fp_line
			(start -0.508 -0.9398)
			(end -0.508 0.9398)
			(stroke
				(width 0.1524)
				(type default)
			)
			(layer "F.SilkS")
		)
		(fp_line
			(start 0.508 -0.9398)
			(end -0.508 -0.9398)
			(stroke
				(width 0.1524)
				(type default)
			)
			(layer "F.SilkS")
		)
		(fp_rect
			(start -0.508 0.9398)
			(end 0.508 -0.9398)
			(stroke
				(width 0)
				(type default)
			)
			(fill no)
			(layer "F.CrtYd")
		)
		(fp_rect
			(start -0.508 0.9398)
			(end 0.508 -0.9398)
			(stroke
				(width 0)
				(type default)
			)
			(fill no)
			(layer "F.Fab")
		)
		(pad "1" smd custom
			(at 0 -0.4445)
			(size 0.1397 0.1397)
			(layers "F.Cu" "F.Mask" "F.Paste")
			(net "SW_HDD5_N")
			(options
				(clearance outline)
				(anchor circle)
			)
			(primitives
				(gr_poly
					(pts
						(arc
							(start -0.1778 -0.2794)
							(mid -0.249642 -0.249642)
							(end -0.2794 -0.1778)
						)
						(arc
							(start -0.2794 0.1778)
							(mid -0.249642 0.249642)
							(end -0.1778 0.2794)
						)
						(arc
							(start 0.1778 0.2794)
							(mid 0.249642 0.249642)
							(end 0.2794 0.1778)
						)
						(arc
							(start 0.2794 -0.1778)
							(mid 0.249642 -0.249642)
							(end 0.1778 -0.2794)
						)
					)
					(width 0)
					(fill yes)
				)
			)
		)
		(pad "2" smd custom
			(at 0 0.4445)
			(size 0.1397 0.1397)
			(layers "F.Cu" "F.Mask" "F.Paste")
			(net "P12V")
			(options
				(clearance outline)
				(anchor circle)
			)
			(primitives
				(gr_poly
					(pts
						(arc
							(start -0.1778 -0.2794)
							(mid -0.249642 -0.249642)
							(end -0.2794 -0.1778)
						)
						(arc
							(start -0.2794 0.1778)
							(mid -0.249642 0.249642)
							(end -0.1778 0.2794)
						)
						(arc
							(start 0.1778 0.2794)
							(mid 0.249642 0.249642)
							(end 0.2794 0.1778)
						)
						(arc
							(start 0.2794 -0.1778)
							(mid 0.249642 -0.249642)
							(end 0.1778 -0.2794)
						)
					)
					(width 0)
					(fill yes)
				)
			)
		)
	)
	(footprint ""
		(layer "F.Cu")
		(at 234.753912 -42.779696 90)
		(property "Reference" "R158"
			(at 0 0 90)
			(layer "F.SilkS")
			(hide yes)
			(effects
				(font
					(size 1.27 1.27)
				)
			)
		)
		(property "Value" "0R2J-2-GP"
			(at 0.064008 -3.993896 90)
			(unlocked yes)
			(layer "F.Fab")
			(hide yes)
			(effects
				(font
					(size 1.016 1.016)
					(thickness 0.1524)
				)
			)
		)
		(property "Device Type" "R402H16"
			(at 0.064008 -5.517896 90)
			(unlocked yes)
			(layer "F.Fab")
			(hide yes)
			(effects
				(font
					(size 1.016 1.016)
					(thickness 0.1524)
				)
			)
		)
		(duplicate_pad_numbers_are_jumpers no)
		(fp_line
			(start 0.508 -0.9398)
			(end -0.508 -0.9398)
			(stroke
				(width 0.1524)
				(type default)
			)
			(layer "F.SilkS")
		)
		(fp_line
			(start -0.508 -0.9398)
			(end -0.508 0.9398)
			(stroke
				(width 0.1524)
				(type default)
			)
			(layer "F.SilkS")
		)
		(fp_rect
			(start -0.508 0.9398)
			(end 0.508 -0.9398)
			(stroke
				(width 0)
				(type default)
			)
			(fill no)
			(layer "F.CrtYd")
		)
		(fp_rect
			(start -0.508 0.9398)
			(end 0.508 -0.9398)
			(stroke
				(width 0)
				(type default)
			)
			(fill no)
			(layer "F.Fab")
		)
		(pad "1" smd custom
			(at 0 -0.4445 90)
			(size 0.1397 0.1397)
			(layers "F.Cu" "F.Mask" "F.Paste")
			(net "DRV_ACT_NET4")
			(options
				(clearance outline)
				(anchor circle)
			)
			(primitives
				(gr_poly
					(pts
						(arc
							(start -0.1778 -0.2794)
							(mid -0.249642 -0.249642)
							(end -0.2794 -0.1778)
						)
						(arc
							(start -0.2794 0.1778)
							(mid -0.249642 0.249642)
							(end -0.1778 0.2794)
						)
						(arc
							(start 0.1778 0.2794)
							(mid 0.249642 0.249642)
							(end 0.2794 0.1778)
						)
						(arc
							(start 0.2794 -0.1778)
							(mid 0.249642 -0.249642)
							(end 0.1778 -0.2794)
						)
					)
					(width 0)
					(fill yes)
				)
			)
		)
		(pad "2" smd custom
			(at 0 0.4445 90)
			(size 0.1397 0.1397)
			(layers "F.Cu" "F.Mask" "F.Paste")
			(net "DRIVE_ACT_4")
			(options
				(clearance outline)
				(anchor circle)
			)
			(primitives
				(gr_poly
					(pts
						(arc
							(start -0.1778 -0.2794)
							(mid -0.249642 -0.249642)
							(end -0.2794 -0.1778)
						)
						(arc
							(start -0.2794 0.1778)
							(mid -0.249642 0.249642)
							(end -0.1778 0.2794)
						)
						(arc
							(start 0.1778 0.2794)
							(mid 0.249642 0.249642)
							(end 0.2794 0.1778)
						)
						(arc
							(start 0.2794 -0.1778)
							(mid 0.249642 -0.249642)
							(end 0.1778 -0.2794)
						)
					)
					(width 0)
					(fill yes)
				)
			)
		)
	)
	(footprint ""
		(layer "F.Cu")
		(at 207.390746 -40.9067 180)
		(property "Reference" "R331"
			(at 0 0 180)
			(layer "F.SilkS")
			(hide yes)
			(effects
				(font
					(size 1.27 1.27)
				)
			)
		)
		(property "Value" "4K7R2J-2-GP"
			(at 0.064008 -3.993896 180)
			(unlocked yes)
			(layer "F.Fab")
			(hide yes)
			(effects
				(font
					(size 1.016 1.016)
					(thickness 0.1524)
				)
			)
		)
		(property "Device Type" "R402H16"
			(at 0.064008 -5.517896 180)
			(unlocked yes)
			(layer "F.Fab")
			(hide yes)
			(effects
				(font
					(size 1.016 1.016)
					(thickness 0.1524)
				)
			)
		)
		(duplicate_pad_numbers_are_jumpers no)
		(fp_line
			(start 0.508 -0.9398)
			(end -0.508 -0.9398)
			(stroke
				(width 0.1524)
				(type default)
			)
			(layer "F.SilkS")
		)
		(fp_line
			(start -0.508 -0.9398)
			(end -0.508 0.9398)
			(stroke
				(width 0.1524)
				(type default)
			)
			(layer "F.SilkS")
		)
		(fp_rect
			(start -0.508 0.9398)
			(end 0.508 -0.9398)
			(stroke
				(width 0)
				(type default)
			)
			(fill no)
			(layer "F.CrtYd")
		)
		(fp_rect
			(start -0.508 0.9398)
			(end 0.508 -0.9398)
			(stroke
				(width 0)
				(type default)
			)
			(fill no)
			(layer "F.Fab")
		)
		(pad "1" smd custom
			(at 0 -0.4445 180)
			(size 0.1397 0.1397)
			(layers "F.Cu" "F.Mask" "F.Paste")
			(net "P3V3")
			(options
				(clearance outline)
				(anchor circle)
			)
			(primitives
				(gr_poly
					(pts
						(arc
							(start -0.1778 -0.2794)
							(mid -0.249642 -0.249642)
							(end -0.2794 -0.1778)
						)
						(arc
							(start -0.2794 0.1778)
							(mid -0.249642 0.249642)
							(end -0.1778 0.2794)
						)
						(arc
							(start 0.1778 0.2794)
							(mid 0.249642 0.249642)
							(end 0.2794 0.1778)
						)
						(arc
							(start 0.2794 -0.1778)
							(mid 0.249642 -0.249642)
							(end 0.1778 -0.2794)
						)
					)
					(width 0)
					(fill yes)
				)
			)
		)
		(pad "2" smd custom
			(at 0 0.4445 180)
			(size 0.1397 0.1397)
			(layers "F.Cu" "F.Mask" "F.Paste")
			(net "I2C_B_TMP4_A2")
			(options
				(clearance outline)
				(anchor circle)
			)
			(primitives
				(gr_poly
					(pts
						(arc
							(start -0.1778 -0.2794)
							(mid -0.249642 -0.249642)
							(end -0.2794 -0.1778)
						)
						(arc
							(start -0.2794 0.1778)
							(mid -0.249642 0.249642)
							(end -0.1778 0.2794)
						)
						(arc
							(start 0.1778 0.2794)
							(mid 0.249642 0.249642)
							(end 0.2794 0.1778)
						)
						(arc
							(start 0.2794 -0.1778)
							(mid 0.249642 -0.249642)
							(end 0.1778 -0.2794)
						)
					)
					(width 0)
					(fill yes)
				)
			)
		)
	)
	(footprint ""
		(layer "F.Cu")
		(at 27.939746 -221.6277)
		(property "Reference" "TP37"
			(at 0 0 0)
			(layer "F.SilkS")
			(hide yes)
			(effects
				(font
					(size 1.27 1.27)
				)
			)
		)
		(property "Value" "TPAD32-GP"
			(at 0 -3.166364 0)
			(unlocked yes)
			(layer "F.Fab")
			(hide yes)
			(effects
				(font
					(size 1.016 1.016)
					(thickness 0.1524)
				)
			)
		)
		(property "Device Type" "TPAD32"
			(at 0 -4.690618 0)
			(unlocked yes)
			(layer "F.Fab")
			(hide yes)
			(effects
				(font
					(size 1.016 1.016)
					(thickness 0.1524)
				)
			)
		)
		(duplicate_pad_numbers_are_jumpers no)
		(fp_poly
			(pts
				(arc
					(start 0.4064 0)
					(mid -0.4064 0)
					(end 0.4064 0)
				)
			)
			(stroke
				(width 0)
				(type default)
			)
			(fill no)
			(layer "F.CrtYd")
		)
		(fp_poly
			(pts
				(arc
					(start 0.7112 0)
					(mid -0.7112 0)
					(end 0.7112 0)
				)
			)
			(stroke
				(width 0)
				(type default)
			)
			(fill no)
			(layer "F.Fab")
		)
		(pad "1" smd circle
			(at 0 0)
			(size 0.8128 0.8128)
			(layers "F.Cu" "F.Mask" "F.Paste")
			(net "ACT_HDD12")
		)
	)
	(footprint ""
		(layer "F.Cu")
		(at 224.0788 -440.3852 90)
		(property "Reference" "PC40"
			(at 0 0 90)
			(layer "F.SilkS")
			(hide yes)
			(effects
				(font
					(size 1.27 1.27)
				)
			)
		)
		(property "Value" "SC4D7U50V6KX-L2-GP"
			(at 0 -6.8072 90)
			(unlocked yes)
			(layer "F.Fab")
			(hide yes)
			(effects
				(font
					(size 1.016 1.016)
					(thickness 0.1524)
				)
			)
		)
		(property "Device Type" "C1206H38"
			(at 0 -8.7122 90)
			(unlocked yes)
			(layer "F.Fab")
			(hide yes)
			(effects
				(font
					(size 1.016 1.016)
					(thickness 0.1524)
				)
			)
		)
		(duplicate_pad_numbers_are_jumpers no)
		(fp_line
			(start 1.016 -2.2352)
			(end -1.016 -2.2352)
			(stroke
				(width 0.1524)
				(type default)
			)
			(layer "F.SilkS")
		)
		(fp_line
			(start 1.016 -2.2352)
			(end 1.016 -0.8382)
			(stroke
				(width 0.1524)
				(type default)
			)
			(layer "F.SilkS")
		)
		(fp_line
			(start -1.016 -2.2352)
			(end -1.016 -0.8382)
			(stroke
				(width 0.1524)
				(type default)
			)
			(layer "F.SilkS")
		)
		(fp_line
			(start 1.016 0.8382)
			(end 1.016 2.2352)
			(stroke
				(width 0.1524)
				(type default)
			)
			(layer "F.SilkS")
		)
		(fp_line
			(start 1.016 2.2352)
			(end -1.016 2.2352)
			(stroke
				(width 0.1524)
				(type default)
			)
			(layer "F.SilkS")
		)
		(fp_line
			(start -1.016 2.2352)
			(end -1.016 0.8128)
			(stroke
				(width 0.1524)
				(type default)
			)
			(layer "F.SilkS")
		)
		(fp_rect
			(start -1.0922 2.3114)
			(end 1.0922 -2.3114)
			(stroke
				(width 0)
				(type default)
			)
			(fill no)
			(layer "F.CrtYd")
		)
		(fp_poly
			(pts
				(xy -1.0922 -2.3114) (xy 1.0922 -2.3114) (xy 1.0922 2.3114) (xy -1.0922 2.3114)
			)
			(stroke
				(width 0)
				(type default)
			)
			(fill no)
			(layer "F.Fab")
		)
		(pad "1" smd rect
			(at 0 -1.397 90)
			(size 1.651 1.27)
			(layers "F.Cu" "F.Mask" "F.Paste")
			(net "P3V3_IN")
		)
		(pad "2" smd rect
			(at 0 1.397 90)
			(size 1.651 1.27)
			(layers "F.Cu" "F.Mask" "F.Paste")
			(net "GND")
		)
	)
	(footprint ""
		(layer "F.Cu")
		(at 215.259412 -71.354696 90)
		(property "Reference" "R162"
			(at 0 0 90)
			(layer "F.SilkS")
			(hide yes)
			(effects
				(font
					(size 1.27 1.27)
				)
			)
		)
		(property "Value" "4K7R2J-2-GP"
			(at 0.064008 -3.993896 90)
			(unlocked yes)
			(layer "F.Fab")
			(hide yes)
			(effects
				(font
					(size 1.016 1.016)
					(thickness 0.1524)
				)
			)
		)
		(property "Device Type" "R402H16"
			(at 0.064008 -5.517896 90)
			(unlocked yes)
			(layer "F.Fab")
			(hide yes)
			(effects
				(font
					(size 1.016 1.016)
					(thickness 0.1524)
				)
			)
		)
		(duplicate_pad_numbers_are_jumpers no)
		(fp_line
			(start 0.508 -0.9398)
			(end -0.508 -0.9398)
			(stroke
				(width 0.1524)
				(type default)
			)
			(layer "F.SilkS")
		)
		(fp_line
			(start -0.508 -0.9398)
			(end -0.508 0.9398)
			(stroke
				(width 0.1524)
				(type default)
			)
			(layer "F.SilkS")
		)
		(fp_rect
			(start -0.508 0.9398)
			(end 0.508 -0.9398)
			(stroke
				(width 0)
				(type default)
			)
			(fill no)
			(layer "F.CrtYd")
		)
		(fp_rect
			(start -0.508 0.9398)
			(end 0.508 -0.9398)
			(stroke
				(width 0)
				(type default)
			)
			(fill no)
			(layer "F.Fab")
		)
		(pad "1" smd custom
			(at 0 -0.4445 90)
			(size 0.1397 0.1397)
			(layers "F.Cu" "F.Mask" "F.Paste")
			(net "P3V3")
			(options
				(clearance outline)
				(anchor circle)
			)
			(primitives
				(gr_poly
					(pts
						(arc
							(start -0.1778 -0.2794)
							(mid -0.249642 -0.249642)
							(end -0.2794 -0.1778)
						)
						(arc
							(start -0.2794 0.1778)
							(mid -0.249642 0.249642)
							(end -0.1778 0.2794)
						)
						(arc
							(start 0.1778 0.2794)
							(mid 0.249642 0.249642)
							(end 0.2794 0.1778)
						)
						(arc
							(start 0.2794 -0.1778)
							(mid 0.249642 -0.249642)
							(end 0.1778 -0.2794)
						)
					)
					(width 0)
					(fill yes)
				)
			)
		)
		(pad "2" smd custom
			(at 0 0.4445 90)
			(size 0.1397 0.1397)
			(layers "F.Cu" "F.Mask" "F.Paste")
			(net "HDD_PRSNT_NET4")
			(options
				(clearance outline)
				(anchor circle)
			)
			(primitives
				(gr_poly
					(pts
						(arc
							(start -0.1778 -0.2794)
							(mid -0.249642 -0.249642)
							(end -0.2794 -0.1778)
						)
						(arc
							(start -0.2794 0.1778)
							(mid -0.249642 0.249642)
							(end -0.1778 0.2794)
						)
						(arc
							(start 0.1778 0.2794)
							(mid 0.249642 0.249642)
							(end 0.2794 0.1778)
						)
						(arc
							(start 0.2794 -0.1778)
							(mid 0.249642 -0.249642)
							(end 0.1778 -0.2794)
						)
					)
					(width 0)
					(fill yes)
				)
			)
		)
	)
)
